(kicad_pcb
	(version 20260206)
	(generator "pcbnew")
	(generator_version "10.0")
	(general
		(thickness 1.6)
		(legacy_teardrops no)
	)
	(paper "A4")
	(title_block
		(title "01162023_DA0F0TEBIF0_F0T_Expander_BD_F_brd_V02_OCP.brd")
		(comment 1 "Grand Teton / footprints 5425-5431 of 9728")
	)
	(layers
		(0 "F.Cu" signal "TOP")
		(4 "In1.Cu" signal "GND")
		(6 "In2.Cu" signal "VCC")
		(8 "In3.Cu" signal "VCC1")
		(10 "In4.Cu" signal "GND1")
		(12 "In5.Cu" signal "IN1")
		(14 "In6.Cu" signal "GND2")
		(16 "In7.Cu" signal "IN2")
		(18 "In8.Cu" signal "GND3")
		(20 "In9.Cu" signal "IN3")
		(22 "In10.Cu" signal "GND4")
		(24 "In11.Cu" signal "IN4")
		(26 "In12.Cu" signal "GND5")
		(28 "In13.Cu" signal "IN5")
		(30 "In14.Cu" signal "GND6")
		(32 "In15.Cu" signal "IN6")
		(34 "In16.Cu" signal "GND7")
		(2 "B.Cu" signal "BOTTOM")
		(9 "F.Adhes" user "F.Adhesive")
		(11 "B.Adhes" user "B.Adhesive")
		(13 "F.Paste" user "Package Geometry/Pastemask Top")
		(15 "B.Paste" user "Package Geometry/Pastemask Bottom")
		(5 "F.SilkS" user "Ref Des/Silkscreen Top")
		(7 "B.SilkS" user "Ref Des/Silkscreen Bottom")
		(1 "F.Mask" user "Board Geometry/Soldermask Top")
		(3 "B.Mask" user "Board Geometry/Soldermask Bottom")
		(17 "Dwgs.User" user "User.Drawings")
		(19 "Cmts.User" user "User.Comments")
		(21 "Eco1.User" user "User.Eco1")
		(23 "Eco2.User" user "User.Eco2")
		(25 "Edge.Cuts" user "Board Geometry/Outline")
		(27 "Margin" user)
		(31 "F.CrtYd" user "Package Geometry/Place Bound Top")
		(29 "B.CrtYd" user "Package Geometry/Place Bound Bottom")
		(35 "F.Fab" user "Ref Des/Assembly Top")
		(33 "B.Fab" user "Ref Des/Assembly Bottom")
	)
	(footprint ""
		(layer "F.Cu")
		(at 120.947942 -40.037258 90)
		(property "Reference" "U367"
			(at 0.247142 2.344928 90)
			(unlocked yes)
			(layer "F.SilkS")
			(effects
				(font
					(size 0.7874 0.5842)
					(thickness 0.1524)
				)
			)
		)
		(property "Value" ""
			(at 0 0 90)
			(layer "F.Fab")
			(effects
				(font
					(size 1.27 1.27)
				)
			)
		)
		(duplicate_pad_numbers_are_jumpers no)
		(fp_line
			(start -1.949958 -1.610106)
			(end 1.949958 -1.610106)
			(stroke
				(width 0.1524)
				(type default)
			)
			(layer "F.SilkS")
		)
		(fp_line
			(start 1.949958 -1.560068)
			(end 1.949958 1.610106)
			(stroke
				(width 0.1524)
				(type default)
			)
			(layer "F.SilkS")
		)
		(fp_line
			(start 1.949958 1.610106)
			(end -1.949958 1.610106)
			(stroke
				(width 0.1524)
				(type default)
			)
			(layer "F.SilkS")
		)
		(fp_line
			(start -1.949958 1.610106)
			(end -1.949958 -1.610106)
			(stroke
				(width 0.1524)
				(type default)
			)
			(layer "F.SilkS")
		)
		(fp_line
			(start 0.750062 -1.560068)
			(end 0.750062 1.560068)
			(stroke
				(width 0.1)
				(type default)
			)
			(layer "F.Fab")
		)
		(fp_line
			(start -0.750062 -1.560068)
			(end 0.750062 -1.560068)
			(stroke
				(width 0.1)
				(type default)
			)
			(layer "F.Fab")
		)
		(fp_line
			(start 0.750062 1.560068)
			(end -0.750062 1.560068)
			(stroke
				(width 0.1)
				(type default)
			)
			(layer "F.Fab")
		)
		(fp_line
			(start -0.750062 1.560068)
			(end -0.750062 -1.560068)
			(stroke
				(width 0.1)
				(type default)
			)
			(layer "F.Fab")
		)
		(pad "D" smd rect
			(at 1.100074 0)
			(size 1.016 1.4224)
			(layers "F.Cu" "F.Mask" "F.Paste")
			(net "SSD4_AUX_P3V3_EN")
		)
		(pad "G" smd rect
			(at -1.100074 -0.94996)
			(size 1.016 1.4224)
			(layers "F.Cu" "F.Mask" "F.Paste")
			(net "PRSNT_SSD4_R1_N")
		)
		(pad "S" smd rect
			(at -1.100074 0.94996)
			(size 1.016 1.4224)
			(layers "F.Cu" "F.Mask" "F.Paste")
			(net "GND")
		)
	)
	(footprint ""
		(layer "F.Cu")
		(at 98.575368 -69.47916 180)
		(property "Reference" "PU77"
			(at -1.959102 3.72364 90)
			(unlocked yes)
			(layer "F.SilkS")
			(effects
				(font
					(size 0.7874 0.5842)
					(thickness 0.1524)
				)
			)
		)
		(property "Value" ""
			(at 0 0 180)
			(layer "F.Fab")
			(effects
				(font
					(size 1.27 1.27)
				)
			)
		)
		(duplicate_pad_numbers_are_jumpers no)
		(fp_line
			(start 1.239774 1.495298)
			(end -1.239774 1.495298)
			(stroke
				(width 0.1524)
				(type default)
			)
			(layer "F.SilkS")
		)
		(fp_line
			(start 1.239774 -1.495298)
			(end 1.239774 1.495298)
			(stroke
				(width 0.1524)
				(type default)
			)
			(layer "F.SilkS")
		)
		(fp_line
			(start -1.239774 1.495298)
			(end -1.239774 -1.495298)
			(stroke
				(width 0.1524)
				(type default)
			)
			(layer "F.SilkS")
		)
		(fp_line
			(start -1.239774 -1.495298)
			(end 1.239774 -1.495298)
			(stroke
				(width 0.1524)
				(type default)
			)
			(layer "F.SilkS")
		)
		(fp_poly
			(pts
				(xy -1.720342 -1.176782) (xy -2.438654 -0.45847) (xy -1.361186 -0.099314)
			)
			(stroke
				(width 0)
				(type default)
			)
			(fill yes)
			(layer "F.SilkS")
		)
		(fp_line
			(start 0.8001 1.050036)
			(end -0.8001 1.050036)
			(stroke
				(width 0.1)
				(type default)
			)
			(layer "F.Fab")
		)
		(fp_line
			(start 0.8001 -1.050036)
			(end 0.8001 1.050036)
			(stroke
				(width 0.1)
				(type default)
			)
			(layer "F.Fab")
		)
		(fp_line
			(start -0.8001 1.050036)
			(end -0.8001 -1.050036)
			(stroke
				(width 0.1)
				(type default)
			)
			(layer "F.Fab")
		)
		(fp_line
			(start -0.8001 -1.050036)
			(end 0.8001 -1.050036)
			(stroke
				(width 0.1)
				(type default)
			)
			(layer "F.Fab")
		)
		(fp_poly
			(pts
				(xy -2.458974 -0.508) (xy -2.458974 0.508) (xy -1.442974 0)
			)
			(stroke
				(width 0)
				(type default)
			)
			(fill yes)
			(layer "F.Fab")
		)
		(pad "1_2" smd circle
			(at -0.374904 0 270)
			(size 0 0)
			(layers "F.Cu" "F.Mask" "F.Paste")
			(net "P12V_AUX")
		)
		(pad "3" smd rect
			(at -0.499872 0.999998 180)
			(size 0.254 0.7112)
			(layers "F.Cu" "F.Mask" "F.Paste")
			(net "GND")
		)
		(pad "4" smd rect
			(at 0 0.999998 180)
			(size 0.254 0.7112)
			(layers "F.Cu" "F.Mask" "F.Paste")
			(net "P12V_SSD3_CO_ILIMIT")
		)
		(pad "5" smd rect
			(at 0.499872 0.999998 180)
			(size 0.254 0.7112)
			(layers "F.Cu" "F.Mask" "F.Paste")
			(net "P12V_SSD3_CO_MODE")
		)
		(pad "6_7" smd circle
			(at 0.374904 0 90)
			(size 0 0)
			(layers "F.Cu" "F.Mask" "F.Paste")
			(net "P12V_SSD3_R")
		)
		(pad "8" smd rect
			(at 0.499872 -0.999998 180)
			(size 0.254 0.7112)
			(layers "F.Cu" "F.Mask" "F.Paste")
			(net "P12V_SSD3_CO_GATE")
		)
		(pad "9" smd rect
			(at 0 -0.999998 180)
			(size 0.254 0.7112)
			(layers "F.Cu" "F.Mask" "F.Paste")
			(net "P12V_SSD3_CO_EN")
		)
		(pad "10" smd rect
			(at -0.499872 -0.999998 180)
			(size 0.254 0.7112)
			(layers "F.Cu" "F.Mask" "F.Paste")
			(net "P12V_SSD3_CO_DV_DT")
		)
	)
	(footprint ""
		(layer "F.Cu")
		(at 241.624612 -60.845192 -90)
		(property "Reference" "R5994"
			(at 0 0 270)
			(layer "F.SilkS")
			(hide yes)
			(effects
				(font
					(size 1.27 1.27)
				)
			)
		)
		(property "Value" ""
			(at 0 0 270)
			(layer "F.Fab")
			(effects
				(font
					(size 1.27 1.27)
				)
			)
		)
		(duplicate_pad_numbers_are_jumpers no)
		(fp_line
			(start -0.7874 0.4064)
			(end -0.7874 -0.4064)
			(stroke
				(width 0.1524)
				(type default)
			)
			(layer "F.SilkS")
		)
		(fp_line
			(start 0.7874 0.4064)
			(end -0.7874 0.4064)
			(stroke
				(width 0.1524)
				(type default)
			)
			(layer "F.SilkS")
		)
		(fp_line
			(start -0.7874 -0.4064)
			(end 0.7874 -0.4064)
			(stroke
				(width 0.1524)
				(type default)
			)
			(layer "F.SilkS")
		)
		(fp_line
			(start 0.7874 -0.4064)
			(end 0.7874 0.4064)
			(stroke
				(width 0.1524)
				(type default)
			)
			(layer "F.SilkS")
		)
		(fp_line
			(start -0.67945 0.3048)
			(end -0.67945 -0.305054)
			(stroke
				(width 0.1)
				(type default)
			)
			(layer "F.Fab")
		)
		(fp_line
			(start -0.12065 0.3048)
			(end -0.67945 0.3048)
			(stroke
				(width 0.1)
				(type default)
			)
			(layer "F.Fab")
		)
		(fp_line
			(start 0.120396 0.3048)
			(end 0.120396 0.2794)
			(stroke
				(width 0.1)
				(type default)
			)
			(layer "F.Fab")
		)
		(fp_line
			(start 0.67945 0.3048)
			(end 0.120396 0.3048)
			(stroke
				(width 0.1)
				(type default)
			)
			(layer "F.Fab")
		)
		(fp_line
			(start -0.12065 0.2794)
			(end -0.12065 0.3048)
			(stroke
				(width 0.1)
				(type default)
			)
			(layer "F.Fab")
		)
		(fp_line
			(start 0.120396 0.2794)
			(end -0.12065 0.2794)
			(stroke
				(width 0.1)
				(type default)
			)
			(layer "F.Fab")
		)
		(fp_line
			(start -0.12065 -0.2794)
			(end 0.12065 -0.2794)
			(stroke
				(width 0.1)
				(type default)
			)
			(layer "F.Fab")
		)
		(fp_line
			(start 0.12065 -0.2794)
			(end 0.12065 -0.3048)
			(stroke
				(width 0.1)
				(type default)
			)
			(layer "F.Fab")
		)
		(fp_line
			(start 0.12065 -0.3048)
			(end 0.67945 -0.3048)
			(stroke
				(width 0.1)
				(type default)
			)
			(layer "F.Fab")
		)
		(fp_line
			(start 0.67945 -0.3048)
			(end 0.67945 0.3048)
			(stroke
				(width 0.1)
				(type default)
			)
			(layer "F.Fab")
		)
		(fp_line
			(start -0.67945 -0.305054)
			(end -0.12065 -0.305054)
			(stroke
				(width 0.1)
				(type default)
			)
			(layer "F.Fab")
		)
		(fp_line
			(start -0.12065 -0.305054)
			(end -0.12065 -0.2794)
			(stroke
				(width 0.1)
				(type default)
			)
			(layer "F.Fab")
		)
		(pad "1" smd circle
			(at -0.40005 0 270)
			(size 0 0)
			(layers "F.Cu" "F.Mask" "F.Paste")
			(net "PWRGD_P12V_SSD8_D")
		)
		(pad "2" smd circle
			(at 0.40005 0 270)
			(size 0 0)
			(layers "F.Cu" "F.Mask" "F.Paste")
			(net "PWRGD_P12V_SSD8_R")
		)
	)
	(footprint ""
		(layer "F.Cu")
		(at 118.94058 -122.123454)
		(property "Reference" "PC595"
			(at 0 0 0)
			(layer "F.SilkS")
			(hide yes)
			(effects
				(font
					(size 1.27 1.27)
				)
			)
		)
		(property "Value" ""
			(at 0 0 0)
			(layer "F.Fab")
			(effects
				(font
					(size 1.27 1.27)
				)
			)
		)
		(duplicate_pad_numbers_are_jumpers no)
		(fp_line
			(start -1.524 -0.762)
			(end 1.524 -0.762)
			(stroke
				(width 0.1524)
				(type default)
			)
			(layer "F.SilkS")
		)
		(fp_line
			(start -1.524 0.762)
			(end -1.524 -0.762)
			(stroke
				(width 0.1524)
				(type default)
			)
			(layer "F.SilkS")
		)
		(fp_line
			(start 1.524 -0.762)
			(end 1.524 0.762)
			(stroke
				(width 0.1524)
				(type default)
			)
			(layer "F.SilkS")
		)
		(fp_line
			(start 1.524 0.762)
			(end -1.524 0.762)
			(stroke
				(width 0.1524)
				(type default)
			)
			(layer "F.SilkS")
		)
		(fp_line
			(start -1.1049 -0.724916)
			(end -1.1049 0.724916)
			(stroke
				(width 0.1)
				(type default)
			)
			(layer "F.Fab")
		)
		(fp_line
			(start -1.1049 0.724916)
			(end 1.1049 0.724916)
			(stroke
				(width 0.1)
				(type default)
			)
			(layer "F.Fab")
		)
		(fp_line
			(start 1.1049 -0.724916)
			(end -1.1049 -0.724916)
			(stroke
				(width 0.1)
				(type default)
			)
			(layer "F.Fab")
		)
		(fp_line
			(start 1.1049 0.724916)
			(end 1.1049 -0.724916)
			(stroke
				(width 0.1)
				(type default)
			)
			(layer "F.Fab")
		)
		(pad "1" smd rect
			(at -0.889 0 180)
			(size 1.016 1.27)
			(layers "F.Cu" "F.Mask" "F.Paste")
			(net "P3V3")
		)
		(pad "2" smd rect
			(at 0.889 0 180)
			(size 1.016 1.27)
			(layers "F.Cu" "F.Mask" "F.Paste")
			(net "GND")
		)
	)
	(footprint ""
		(layer "F.Cu")
		(at 361.832652 -396.50035 180)
		(property "Reference" "Q246"
			(at -0.790448 -1.975358 0)
			(unlocked yes)
			(layer "F.SilkS")
			(effects
				(font
					(size 0.7874 0.5842)
					(thickness 0.1524)
				)
			)
		)
		(property "Value" ""
			(at 0 0 180)
			(layer "F.Fab")
			(effects
				(font
					(size 1.27 1.27)
				)
			)
		)
		(duplicate_pad_numbers_are_jumpers no)
		(fp_line
			(start 1.376172 1.199896)
			(end -1.376172 1.199896)
			(stroke
				(width 0.1524)
				(type default)
			)
			(layer "F.SilkS")
		)
		(fp_line
			(start 1.376172 -1.199896)
			(end 1.376172 1.199896)
			(stroke
				(width 0.1524)
				(type default)
			)
			(layer "F.SilkS")
		)
		(fp_line
			(start 0.508 -1.199896)
			(end 1.376172 -1.199896)
			(stroke
				(width 0.1524)
				(type default)
			)
			(layer "F.SilkS")
		)
		(fp_line
			(start 0 -0.762)
			(end 0.508 -1.199896)
			(stroke
				(width 0.1524)
				(type default)
			)
			(layer "F.SilkS")
		)
		(fp_line
			(start -0.508 -1.199896)
			(end 0 -0.762)
			(stroke
				(width 0.1524)
				(type default)
			)
			(layer "F.SilkS")
		)
		(fp_line
			(start -1.376172 1.199896)
			(end -1.376172 -1.199896)
			(stroke
				(width 0.1524)
				(type default)
			)
			(layer "F.SilkS")
		)
		(fp_line
			(start -1.376172 -1.199896)
			(end -0.508 -1.199896)
			(stroke
				(width 0.1524)
				(type default)
			)
			(layer "F.SilkS")
		)
		(fp_poly
			(pts
				(xy -1.4605 -0.7493) (xy -2.2225 -1.1303) (xy -2.2225 -0.3683)
			)
			(stroke
				(width 0)
				(type default)
			)
			(fill yes)
			(layer "F.SilkS")
		)
		(fp_line
			(start 0.674878 1.100074)
			(end -0.674878 1.100074)
			(stroke
				(width 0.1)
				(type default)
			)
			(layer "F.Fab")
		)
		(fp_line
			(start 0.674878 -1.100074)
			(end 0.674878 1.100074)
			(stroke
				(width 0.1)
				(type default)
			)
			(layer "F.Fab")
		)
		(fp_line
			(start -0.674878 1.100074)
			(end -0.674878 -1.100074)
			(stroke
				(width 0.1)
				(type default)
			)
			(layer "F.Fab")
		)
		(fp_line
			(start -0.674878 -1.100074)
			(end 0.674878 -1.100074)
			(stroke
				(width 0.1)
				(type default)
			)
			(layer "F.Fab")
		)
		(fp_poly
			(pts
				(xy -1.4605 -0.7493) (xy -2.2225 -1.1303) (xy -2.2225 -0.3683)
			)
			(stroke
				(width 0)
				(type default)
			)
			(fill yes)
			(layer "F.Fab")
		)
		(pad "1" smd rect
			(at -0.899922 -0.750062 90)
			(size 0.6096 0.6096)
			(layers "F.Cu" "F.Mask" "F.Paste")
			(net "GND")
		)
		(pad "2" smd rect
			(at -0.899922 0 90)
			(size 0.4064 0.6096)
			(layers "F.Cu" "F.Mask" "F.Paste")
			(net "MB_3V3IO_RSVD3")
		)
		(pad "3" smd rect
			(at -0.899922 0.750062 90)
			(size 0.6096 0.6096)
			(layers "F.Cu" "F.Mask" "F.Paste")
			(net "MB_3V3IO_RSVD3_ISO")
		)
		(pad "4" smd rect
			(at 0.899922 0.750062 90)
			(size 0.6096 0.6096)
			(layers "F.Cu" "F.Mask" "F.Paste")
			(net "GND")
		)
		(pad "5" smd rect
			(at 0.899922 0 90)
			(size 0.4064 0.6096)
			(layers "F.Cu" "F.Mask" "F.Paste")
			(net "MB_3V3IO_RSVD3_N")
		)
		(pad "6" smd rect
			(at 0.899922 -0.750062 90)
			(size 0.6096 0.6096)
			(layers "F.Cu" "F.Mask" "F.Paste")
			(net "MB_3V3IO_RSVD3_N")
		)
	)
	(footprint ""
		(layer "F.Cu")
		(at 205.822296 -213.593426)
		(property "Reference" "R5919"
			(at 0 0 0)
			(layer "F.SilkS")
			(hide yes)
			(effects
				(font
					(size 1.27 1.27)
				)
			)
		)
		(property "Value" ""
			(at 0 0 0)
			(layer "F.Fab")
			(effects
				(font
					(size 1.27 1.27)
				)
			)
		)
		(duplicate_pad_numbers_are_jumpers no)
		(fp_line
			(start -0.7874 -0.4064)
			(end 0.7874 -0.4064)
			(stroke
				(width 0.1524)
				(type default)
			)
			(layer "F.SilkS")
		)
		(fp_line
			(start -0.7874 0.4064)
			(end -0.7874 -0.4064)
			(stroke
				(width 0.1524)
				(type default)
			)
			(layer "F.SilkS")
		)
		(fp_line
			(start 0.7874 -0.4064)
			(end 0.7874 0.4064)
			(stroke
				(width 0.1524)
				(type default)
			)
			(layer "F.SilkS")
		)
		(fp_line
			(start 0.7874 0.4064)
			(end -0.7874 0.4064)
			(stroke
				(width 0.1524)
				(type default)
			)
			(layer "F.SilkS")
		)
		(fp_line
			(start -0.67945 -0.305054)
			(end -0.12065 -0.305054)
			(stroke
				(width 0.1)
				(type default)
			)
			(layer "F.Fab")
		)
		(fp_line
			(start -0.67945 0.3048)
			(end -0.67945 -0.305054)
			(stroke
				(width 0.1)
				(type default)
			)
			(layer "F.Fab")
		)
		(fp_line
			(start -0.12065 -0.305054)
			(end -0.12065 -0.2794)
			(stroke
				(width 0.1)
				(type default)
			)
			(layer "F.Fab")
		)
		(fp_line
			(start -0.12065 -0.2794)
			(end 0.12065 -0.2794)
			(stroke
				(width 0.1)
				(type default)
			)
			(layer "F.Fab")
		)
		(fp_line
			(start -0.12065 0.2794)
			(end -0.12065 0.3048)
			(stroke
				(width 0.1)
				(type default)
			)
			(layer "F.Fab")
		)
		(fp_line
			(start -0.12065 0.3048)
			(end -0.67945 0.3048)
			(stroke
				(width 0.1)
				(type default)
			)
			(layer "F.Fab")
		)
		(fp_line
			(start 0.120396 0.2794)
			(end -0.12065 0.2794)
			(stroke
				(width 0.1)
				(type default)
			)
			(layer "F.Fab")
		)
		(fp_line
			(start 0.120396 0.3048)
			(end 0.120396 0.2794)
			(stroke
				(width 0.1)
				(type default)
			)
			(layer "F.Fab")
		)
		(fp_line
			(start 0.12065 -0.3048)
			(end 0.67945 -0.3048)
			(stroke
				(width 0.1)
				(type default)
			)
			(layer "F.Fab")
		)
		(fp_line
			(start 0.12065 -0.2794)
			(end 0.12065 -0.3048)
			(stroke
				(width 0.1)
				(type default)
			)
			(layer "F.Fab")
		)
		(fp_line
			(start 0.67945 -0.3048)
			(end 0.67945 0.3048)
			(stroke
				(width 0.1)
				(type default)
			)
			(layer "F.Fab")
		)
		(fp_line
			(start 0.67945 0.3048)
			(end 0.120396 0.3048)
			(stroke
				(width 0.1)
				(type default)
			)
			(layer "F.Fab")
		)
		(pad "1" smd circle
			(at -0.40005 0)
			(size 0 0)
			(layers "F.Cu" "F.Mask" "F.Paste")
			(net "GND")
		)
		(pad "2" smd circle
			(at 0.40005 0)
			(size 0 0)
			(layers "F.Cu" "F.Mask" "F.Paste")
			(net "BIC_UART_SEL2")
		)
	)
	(footprint ""
		(layer "F.Cu")
		(at 231.499664 -204.44206 90)
		(property "Reference" "R5513"
			(at 0 0 90)
			(layer "F.SilkS")
			(hide yes)
			(effects
				(font
					(size 1.27 1.27)
				)
			)
		)
		(property "Value" ""
			(at 0 0 90)
			(layer "F.Fab")
			(effects
				(font
					(size 1.27 1.27)
				)
			)
		)
		(duplicate_pad_numbers_are_jumpers no)
		(fp_line
			(start 0.7874 -0.4064)
			(end 0.7874 0.4064)
			(stroke
				(width 0.1524)
				(type default)
			)
			(layer "F.SilkS")
		)
		(fp_line
			(start -0.7874 -0.4064)
			(end 0.7874 -0.4064)
			(stroke
				(width 0.1524)
				(type default)
			)
			(layer "F.SilkS")
		)
		(fp_line
			(start 0.7874 0.4064)
			(end -0.7874 0.4064)
			(stroke
				(width 0.1524)
				(type default)
			)
			(layer "F.SilkS")
		)
		(fp_line
			(start -0.7874 0.4064)
			(end -0.7874 -0.4064)
			(stroke
				(width 0.1524)
				(type default)
			)
			(layer "F.SilkS")
		)
		(fp_line
			(start -0.12065 -0.305054)
			(end -0.12065 -0.2794)
			(stroke
				(width 0.1)
				(type default)
			)
			(layer "F.Fab")
		)
		(fp_line
			(start -0.67945 -0.305054)
			(end -0.12065 -0.305054)
			(stroke
				(width 0.1)
				(type default)
			)
			(layer "F.Fab")
		)
		(fp_line
			(start 0.67945 -0.3048)
			(end 0.67945 0.3048)
			(stroke
				(width 0.1)
				(type default)
			)
			(layer "F.Fab")
		)
		(fp_line
			(start 0.12065 -0.3048)
			(end 0.67945 -0.3048)
			(stroke
				(width 0.1)
				(type default)
			)
			(layer "F.Fab")
		)
		(fp_line
			(start 0.12065 -0.2794)
			(end 0.12065 -0.3048)
			(stroke
				(width 0.1)
				(type default)
			)
			(layer "F.Fab")
		)
		(fp_line
			(start -0.12065 -0.2794)
			(end 0.12065 -0.2794)
			(stroke
				(width 0.1)
				(type default)
			)
			(layer "F.Fab")
		)
		(fp_line
			(start 0.120396 0.2794)
			(end -0.12065 0.2794)
			(stroke
				(width 0.1)
				(type default)
			)
			(layer "F.Fab")
		)
		(fp_line
			(start -0.12065 0.2794)
			(end -0.12065 0.3048)
			(stroke
				(width 0.1)
				(type default)
			)
			(layer "F.Fab")
		)
		(fp_line
			(start 0.67945 0.3048)
			(end 0.120396 0.3048)
			(stroke
				(width 0.1)
				(type default)
			)
			(layer "F.Fab")
		)
		(fp_line
			(start 0.120396 0.3048)
			(end 0.120396 0.2794)
			(stroke
				(width 0.1)
				(type default)
			)
			(layer "F.Fab")
		)
		(fp_line
			(start -0.12065 0.3048)
			(end -0.67945 0.3048)
			(stroke
				(width 0.1)
				(type default)
			)
			(layer "F.Fab")
		)
		(fp_line
			(start -0.67945 0.3048)
			(end -0.67945 -0.305054)
			(stroke
				(width 0.1)
				(type default)
			)
			(layer "F.Fab")
		)
		(pad "1" smd circle
			(at -0.40005 0 90)
			(size 0 0)
			(layers "F.Cu" "F.Mask" "F.Paste")
			(net "P3V3_AUX")
		)
		(pad "2" smd circle
			(at 0.40005 0 90)
			(size 0 0)
			(layers "F.Cu" "F.Mask" "F.Paste")
			(net "SPI_BIC1_CLK")
		)
	)
)
